# BASEBOARD_FAB2 (Tioga Pass) — schematic netlist excerpt (pin names and nets, part order shuffled) for the footprints in the layout excerpt that follows; sources: Cadence DE-HDL packaged netlist, KiCad conversion of Wiwynn_Tioga_Pass_MB.brd

Q2U1  FET_N_DUAL  NTJD4001N FET  pkg SMLF  page 95
  SOURCE(0)  = GND
  GATE(0)  = FM_SYS_THROTTLE_LVC3
  DRAIN(0)  = H_CPU0_MEMDEF_MEMHOT_G_N
  SOURCE(0)  = GND
  GATE(0)  = FM_SYS_THROTTLE_LVC3
  DRAIN(0)  = H_CPU0_MEMABC_MEMHOT_G_N

C7P11  CAP  100UF 4V 20% X5R  pkg 0805  page 76 : A = PVCCMCP_CPU1 ; B = GND
R9M4  RES  0.002 1% CHIP  pkg 1206  page 197 : A = P12V_STBY ; B = P12V_NVDIMM_KLM

(kicad_pcb
	(version 20260206)
	(generator "pcbnew")
	(generator_version "10.0")
	(general
		(thickness 1.6)
		(legacy_teardrops no)
	)
	(paper "A4")
	(title_block
		(title "Wiwynn_Tioga_Pass_MB.brd")
		(comment 1 "Tioga Pass / footprints 2387-2389 of 4770")
	)
	(layers
		(0 "F.Cu" signal "TOP")
		(4 "In1.Cu" signal "L2GND")
		(6 "In2.Cu" signal "L3")
		(8 "In3.Cu" signal "L4GND")
		(10 "In4.Cu" signal "L5")
		(12 "In5.Cu" signal "L6GND")
		(14 "In6.Cu" signal "L7VCC")
		(16 "In7.Cu" signal "L8VCC")
		(18 "In8.Cu" signal "L9GND")
		(20 "In9.Cu" signal "L10")
		(22 "In10.Cu" signal "L11GND")
		(24 "In11.Cu" signal "L12")
		(26 "In12.Cu" signal "L13GND")
		(2 "B.Cu" signal "BOTTOM")
		(9 "F.Adhes" user "F.Adhesive")
		(11 "B.Adhes" user "B.Adhesive")
		(13 "F.Paste" user "Package Geometry/Pastemask Top")
		(15 "B.Paste" user "Package Geometry/Pastemask Bottom")
		(5 "F.SilkS" user "Ref Des/Silkscreen Top")
		(7 "B.SilkS" user "Ref Des/Silkscreen Bottom")
		(1 "F.Mask" user "Board Geometry/Soldermask Top")
		(3 "B.Mask" user "Board Geometry/Soldermask Bottom")
		(17 "Dwgs.User" user "User.Drawings")
		(19 "Cmts.User" user "User.Comments")
		(21 "Eco1.User" user "User.Eco1")
		(23 "Eco2.User" user "User.Eco2")
		(25 "Edge.Cuts" user "Board Geometry/Outline")
		(27 "Margin" user)
		(31 "F.CrtYd" user "Package Geometry/Place Bound Top")
		(29 "B.CrtYd" user "Package Geometry/Place Bound Bottom")
		(35 "F.Fab" user "Ref Des/Assembly Top")
		(33 "B.Fab" user "Ref Des/Assembly Bottom")
	)
	(footprint ""
		(layer "B.Cu")
		(at 389.90651 -44.874688)
		(property "Reference" "Q2U1"
			(at 1.51765 0.54864 90)
			(unlocked yes)
			(layer "B.SilkS")
			(effects
				(font
					(size 0.7874 0.5842)
					(thickness 0.1524)
				)
				(justify left mirror)
			)
		)
		(property "Value" ""
			(at 0 0 0)
			(layer "B.Fab")
			(effects
				(font
					(size 1.27 1.27)
				)
				(justify mirror)
			)
		)
		(duplicate_pad_numbers_are_jumpers no)
		(fp_circle
			(center 0.508 -0.7874)
			(end 0.635 -0.7874)
			(stroke
				(width 0.254)
				(type default)
			)
			(fill no)
			(layer "B.SilkS")
		)
		(fp_poly
			(pts
				(xy -0.2159 1.7526) (xy -1.5621 1.7526) (xy -1.5621 -0.4572) (xy -0.2159 -0.4572)
			)
			(stroke
				(width 0)
				(type default)
			)
			(fill no)
			(layer "B.CrtYd")
		)
		(fp_line
			(start -1.5621 -0.45466)
			(end -0.2159 -0.45466)
			(stroke
				(width 0.1)
				(type default)
			)
			(layer "B.Fab")
		)
		(fp_line
			(start -1.5621 1.75514)
			(end -1.5621 -0.45466)
			(stroke
				(width 0.1)
				(type default)
			)
			(layer "B.Fab")
		)
		(fp_line
			(start -0.2159 -0.45466)
			(end -0.2159 1.75514)
			(stroke
				(width 0.1)
				(type default)
			)
			(layer "B.Fab")
		)
		(fp_line
			(start -0.2159 1.75514)
			(end -1.5621 1.75514)
			(stroke
				(width 0.1)
				(type default)
			)
			(layer "B.Fab")
		)
		(fp_circle
			(center 0.508 -0.7874)
			(end 0.635 -0.7874)
			(stroke
				(width 0.254)
				(type default)
			)
			(fill no)
			(layer "B.Fab")
		)
		(pad "1" smd rect
			(at 0 0 180)
			(size 1.016 0.381)
			(layers "B.Cu" "B.Mask" "B.Paste")
			(net "GND")
		)
		(pad "2" smd rect
			(at 0 0.65024 180)
			(size 1.016 0.381)
			(layers "B.Cu" "B.Mask" "B.Paste")
			(net "FM_SYS_THROTTLE_LVC3")
		)
		(pad "3" smd rect
			(at 0 1.30048 180)
			(size 1.016 0.381)
			(layers "B.Cu" "B.Mask" "B.Paste")
			(net "H_CPU0_MEMDEF_MEMHOT_G_N")
		)
		(pad "4" smd rect
			(at -1.778 1.30048 180)
			(size 1.016 0.381)
			(layers "B.Cu" "B.Mask" "B.Paste")
			(net "GND")
		)
		(pad "5" smd rect
			(at -1.778 0.65024 180)
			(size 1.016 0.381)
			(layers "B.Cu" "B.Mask" "B.Paste")
			(net "FM_SYS_THROTTLE_LVC3")
		)
		(pad "6" smd rect
			(at -1.778 0 180)
			(size 1.016 0.381)
			(layers "B.Cu" "B.Mask" "B.Paste")
			(net "H_CPU0_MEMABC_MEMHOT_G_N")
		)
		(zone
			(layer "B.Cu")
			(hatch none 0.5)
			(connect_pads
				(clearance 0)
			)
			(min_thickness 0.25)
			(keepout
				(tracks allowed)
				(vias not_allowed)
				(pads allowed)
				(copperpour not_allowed)
				(footprints allowed)
			)
			(placement
				(enabled no)
				(sheetname "")
			)
			(fill
				(thermal_gap 0.5)
				(thermal_bridge_width 0.5)
				(island_removal_mode 0)
			)
			(polygon
				(pts
					(xy 388.63651 -45.065188) (xy 387.62051 -45.065188) (xy 387.62051 -43.376088) (xy 388.63651 -43.376088)
				)
			)
		)
		(zone
			(layer "B.Cu")
			(hatch none 0.5)
			(connect_pads
				(clearance 0)
			)
			(min_thickness 0.25)
			(keepout
				(tracks allowed)
				(vias not_allowed)
				(pads allowed)
				(copperpour not_allowed)
				(footprints allowed)
			)
			(placement
				(enabled no)
				(sheetname "")
			)
			(fill
				(thermal_gap 0.5)
				(thermal_bridge_width 0.5)
				(island_removal_mode 0)
			)
			(polygon
				(pts
					(xy 390.41451 -45.065188) (xy 389.39851 -45.065188) (xy 389.39851 -43.376088) (xy 390.41451 -43.376088)
				)
			)
		)
	)
	(footprint ""
		(layer "B.Cu")
		(at 9.398 -130.9624 90)
		(property "Reference" "R9M4"
			(at -1.59893 2.286 180)
			(unlocked yes)
			(layer "B.SilkS")
			(effects
				(font
					(size 0.7874 0.5842)
					(thickness 0.1524)
				)
				(justify mirror)
			)
		)
		(property "Value" ""
			(at 0 0 90)
			(layer "B.Fab")
			(effects
				(font
					(size 1.27 1.27)
				)
				(justify mirror)
			)
		)
		(duplicate_pad_numbers_are_jumpers no)
		(fp_line
			(start 0.9017 1.951736)
			(end 0.9017 0.823468)
			(stroke
				(width 0.1524)
				(type default)
			)
			(layer "B.SilkS")
		)
		(fp_line
			(start -0.9017 1.952498)
			(end -0.9017 0.853948)
			(stroke
				(width 0.1524)
				(type default)
			)
			(layer "B.SilkS")
		)
		(fp_poly
			(pts
				(xy 0.9017 -0.3048) (xy -0.9017 -0.3048) (xy -0.9017 3.0988) (xy 0.9017 3.0988)
			)
			(stroke
				(width 0)
				(type default)
			)
			(fill no)
			(layer "B.CrtYd")
		)
		(fp_line
			(start 0.9017 -0.3048)
			(end 0.9017 3.0988)
			(stroke
				(width 0.1)
				(type default)
			)
			(layer "B.Fab")
		)
		(fp_line
			(start -0.9017 -0.3048)
			(end 0.9017 -0.3048)
			(stroke
				(width 0.1)
				(type default)
			)
			(layer "B.Fab")
		)
		(fp_line
			(start 0.9017 3.0988)
			(end -0.9017 3.0988)
			(stroke
				(width 0.1)
				(type default)
			)
			(layer "B.Fab")
		)
		(fp_line
			(start -0.9017 3.0988)
			(end -0.9017 -0.3048)
			(stroke
				(width 0.1)
				(type default)
			)
			(layer "B.Fab")
		)
		(pad "1" smd rect
			(at 0 0 270)
			(size 1.524 1.016)
			(layers "B.Cu" "B.Mask" "B.Paste")
			(net "P12V_STBY")
		)
		(pad "2" smd rect
			(at 0 2.794 270)
			(size 1.524 1.016)
			(layers "B.Cu" "B.Mask" "B.Paste")
			(net "P12V_NVDIMM_KLM")
		)
		(zone
			(layer "B.Cu")
			(hatch none 0.5)
			(connect_pads
				(clearance 0)
			)
			(min_thickness 0.25)
			(keepout
				(tracks allowed)
				(vias not_allowed)
				(pads allowed)
				(copperpour not_allowed)
				(footprints allowed)
			)
			(placement
				(enabled no)
				(sheetname "")
			)
			(fill
				(thermal_gap 0.5)
				(thermal_bridge_width 0.5)
				(island_removal_mode 0)
			)
			(polygon
				(pts
					(xy 9.906 -130.2004) (xy 11.684 -130.2004) (xy 11.684 -131.7244) (xy 9.906 -131.7244)
				)
			)
		)
	)
	(footprint ""
		(layer "B.Cu")
		(at 113.702592 -77.810614)
		(property "Reference" "C7P11"
			(at 0 0 0)
			(layer "B.SilkS")
			(hide yes)
			(effects
				(font
					(size 1.27 1.27)
				)
				(justify mirror)
			)
		)
		(property "Value" ""
			(at 0 0 0)
			(layer "B.Fab")
			(effects
				(font
					(size 1.27 1.27)
				)
				(justify mirror)
			)
		)
		(duplicate_pad_numbers_are_jumpers no)
		(fp_poly
			(pts
				(xy 0.7239 -0.2159) (xy -0.7239 -0.2159) (xy -0.7239 1.9939) (xy 0.7239 1.9939)
			)
			(stroke
				(width 0)
				(type default)
			)
			(fill no)
			(layer "B.CrtYd")
		)
		(fp_line
			(start -0.7239 -0.2159)
			(end 0.7239 -0.2159)
			(stroke
				(width 0.1)
				(type default)
			)
			(layer "B.Fab")
		)
		(fp_line
			(start -0.7239 1.9939)
			(end -0.7239 -0.2159)
			(stroke
				(width 0.1)
				(type default)
			)
			(layer "B.Fab")
		)
		(fp_line
			(start 0.7239 -0.2159)
			(end 0.7239 1.9939)
			(stroke
				(width 0.1)
				(type default)
			)
			(layer "B.Fab")
		)
		(fp_line
			(start 0.7239 1.9939)
			(end -0.7239 1.9939)
			(stroke
				(width 0.1)
				(type default)
			)
			(layer "B.Fab")
		)
		(pad "1" smd rect
			(at 0 0 180)
			(size 1.27 1.016)
			(layers "B.Cu" "B.Mask" "B.Paste")
			(net "PVCCMCP_CPU1")
		)
		(pad "2" smd rect
			(at 0 1.778 180)
			(size 1.27 1.016)
			(layers "B.Cu" "B.Mask" "B.Paste")
			(net "GND")
		)
		(zone
			(layer "B.Cu")
			(hatch none 0.5)
			(connect_pads
				(clearance 0)
			)
			(min_thickness 0.25)
			(keepout
				(tracks not_allowed)
				(vias allowed)
				(pads allowed)
				(copperpour not_allowed)
				(footprints allowed)
			)
			(placement
				(enabled no)
				(sheetname "")
			)
			(fill
				(thermal_gap 0.5)
				(thermal_bridge_width 0.5)
				(island_removal_mode 0)
			)
			(polygon
				(pts
					(xy 114.337592 -77.302614) (xy 113.067592 -77.302614) (xy 113.067592 -76.540614) (xy 114.337592 -76.540614)
				)
			)
		)
	)
)
